(kicad_pcb
	(version 20260206)
	(generator "pcbnew")
	(generator_version "10.0")
	(general
		(thickness 1.6)
		(legacy_teardrops no)
	)
	(paper "A4")
	(title_block
		(title "Bryce Canyon_R.DPB_16317-1_OCP.brd")
		(comment 1 "Bryce Canyon / footprints 669-673 of 2099")
	)
	(layers
		(0 "F.Cu" signal "TOP")
		(4 "In1.Cu" signal "L2GND")
		(6 "In2.Cu" signal "L3")
		(8 "In3.Cu" signal "L4VCC")
		(10 "In4.Cu" signal "L5VCC")
		(12 "In5.Cu" signal "L6")
		(14 "In6.Cu" signal "L7GND")
		(2 "B.Cu" signal "BOTTOM")
		(9 "F.Adhes" user "F.Adhesive")
		(11 "B.Adhes" user "B.Adhesive")
		(13 "F.Paste" user "Package Geometry/Pastemask Top")
		(15 "B.Paste" user "Package Geometry/Pastemask Bottom")
		(5 "F.SilkS" user "Ref Des/Silkscreen Top")
		(7 "B.SilkS" user "Ref Des/Silkscreen Bottom")
		(1 "F.Mask" user "Board Geometry/Soldermask Top")
		(3 "B.Mask" user "Board Geometry/Soldermask Bottom")
		(17 "Dwgs.User" user "User.Drawings")
		(19 "Cmts.User" user "User.Comments")
		(21 "Eco1.User" user "User.Eco1")
		(23 "Eco2.User" user "User.Eco2")
		(25 "Edge.Cuts" user "Board Geometry/Outline")
		(27 "Margin" user)
		(31 "F.CrtYd" user "Package Geometry/Place Bound Top")
		(29 "B.CrtYd" user "Package Geometry/Place Bound Bottom")
		(35 "F.Fab" user "Ref Des/Assembly Top")
		(33 "B.Fab" user "Ref Des/Assembly Bottom")
	)
	(footprint ""
		(layer "F.Cu")
		(at 342.399874 -379.899926 180)
		(property "Reference" "FAN3"
			(at 0 0 180)
			(layer "F.SilkS")
			(hide yes)
			(effects
				(font
					(size 1.27 1.27)
				)
			)
		)
		(property "Value" "MLX-CONN10D-7-GP"
			(at -15.641574 4.697984 180)
			(unlocked yes)
			(layer "F.Fab")
			(hide yes)
			(effects
				(font
					(size 1.016 1.016)
					(thickness 0.1524)
				)
			)
		)
		(property "Device Type" "15-24-6103"
			(at -15.641574 3.173984 180)
			(unlocked yes)
			(layer "F.Fab")
			(hide yes)
			(effects
				(font
					(size 1.016 1.016)
					(thickness 0.1524)
				)
			)
		)
		(duplicate_pad_numbers_are_jumpers no)
		(fp_line
			(start 14.0462 8.1534)
			(end -14.0462 8.1534)
			(stroke
				(width 0.1524)
				(type default)
			)
			(layer "F.SilkS")
		)
		(fp_line
			(start 14.0462 -6.4516)
			(end 14.0462 8.1534)
			(stroke
				(width 0.1524)
				(type default)
			)
			(layer "F.SilkS")
		)
		(fp_line
			(start 9.9314 -6.4516)
			(end 14.0462 -6.4516)
			(stroke
				(width 0.1524)
				(type default)
			)
			(layer "F.SilkS")
		)
		(fp_line
			(start 9.9314 -14.3256)
			(end 9.9314 -6.4516)
			(stroke
				(width 0.1524)
				(type default)
			)
			(layer "F.SilkS")
		)
		(fp_line
			(start -9.9314 -6.4516)
			(end -9.9314 -14.3256)
			(stroke
				(width 0.1524)
				(type default)
			)
			(layer "F.SilkS")
		)
		(fp_line
			(start -9.9314 -14.3256)
			(end 9.9314 -14.3256)
			(stroke
				(width 0.1524)
				(type default)
			)
			(layer "F.SilkS")
		)
		(fp_line
			(start -14.0462 8.1534)
			(end -14.0462 -6.4516)
			(stroke
				(width 0.1524)
				(type default)
			)
			(layer "F.SilkS")
		)
		(fp_line
			(start -14.0462 -6.4516)
			(end -9.9314 -6.4516)
			(stroke
				(width 0.1524)
				(type default)
			)
			(layer "F.SilkS")
		)
		(fp_circle
			(center 8.400034 -7.29996)
			(end 6.761734 -7.29996)
			(stroke
				(width 0.3048)
				(type default)
			)
			(fill no)
			(layer "F.SilkS")
		)
		(fp_circle
			(center 8.400034 -12.800076)
			(end 6.761734 -12.800076)
			(stroke
				(width 0.3048)
				(type default)
			)
			(fill no)
			(layer "F.SilkS")
		)
		(fp_circle
			(center 4.19989 -7.29996)
			(end 2.56159 -7.29996)
			(stroke
				(width 0.3048)
				(type default)
			)
			(fill no)
			(layer "F.SilkS")
		)
		(fp_circle
			(center 4.19989 -12.800076)
			(end 2.56159 -12.800076)
			(stroke
				(width 0.3048)
				(type default)
			)
			(fill no)
			(layer "F.SilkS")
		)
		(fp_circle
			(center 0 -7.29996)
			(end -1.6383 -7.29996)
			(stroke
				(width 0.3048)
				(type default)
			)
			(fill no)
			(layer "F.SilkS")
		)
		(fp_circle
			(center 0 -12.800076)
			(end -1.6383 -12.800076)
			(stroke
				(width 0.3048)
				(type default)
			)
			(fill no)
			(layer "F.SilkS")
		)
		(fp_circle
			(center -4.19989 -7.29996)
			(end -5.83819 -7.29996)
			(stroke
				(width 0.3048)
				(type default)
			)
			(fill no)
			(layer "F.SilkS")
		)
		(fp_circle
			(center -4.19989 -12.800076)
			(end -5.83819 -12.800076)
			(stroke
				(width 0.3048)
				(type default)
			)
			(fill no)
			(layer "F.SilkS")
		)
		(fp_circle
			(center -8.400034 -7.29996)
			(end -10.038334 -7.29996)
			(stroke
				(width 0.3048)
				(type default)
			)
			(fill no)
			(layer "F.SilkS")
		)
		(fp_circle
			(center -8.400034 -12.800076)
			(end -10.038334 -12.800076)
			(stroke
				(width 0.3048)
				(type default)
			)
			(fill no)
			(layer "F.SilkS")
		)
		(fp_poly
			(pts
				(xy -13.7922 7.8994) (xy -13.7922 -6.1976) (xy -9.2964 -6.1976) (xy -9.2964 -13.6906) (xy 9.2964 -13.6906)
				(xy 9.2964 -6.1976) (xy 13.7922 -6.1976) (xy 13.7922 7.8994)
			)
			(stroke
				(width 0)
				(type default)
			)
			(fill no)
			(layer "F.CrtYd")
		)
		(fp_poly
			(pts
				(xy -14.3002 8.4074) (xy -14.3002 -6.7056) (xy -10.1854 -6.7056) (xy -10.1854 -14.5796) (xy 10.1854 -14.5796)
				(xy 10.1854 -6.7056) (xy 14.3002 -6.7056) (xy 14.3002 -0.00635) (xy 13.7922 -0.00635) (xy 13.7922 -6.1976)
				(xy 9.2964 -6.1976) (xy 9.2964 -13.6906) (xy -9.2964 -13.6906) (xy -9.2964 -6.1976) (xy -13.7922 -6.1976)
				(xy -13.7922 7.8994) (xy 13.7922 7.8994) (xy 13.7922 0.00635) (xy 14.3002 0.00635) (xy 14.3002 8.4074)
			)
			(stroke
				(width 0)
				(type default)
			)
			(fill no)
			(layer "F.CrtYd")
		)
		(fp_poly
			(pts
				(xy -14.3002 8.4074) (xy -14.3002 -6.7056) (xy -10.1854 -6.7056) (xy -10.1854 -14.5796) (xy 10.1854 -14.5796)
				(xy 10.1854 -6.7056) (xy 14.3002 -6.7056) (xy 14.3002 8.4074)
			)
			(stroke
				(width 0)
				(type default)
			)
			(fill no)
			(layer "F.Fab")
		)
		(pad "" np_thru_hole circle
			(at -8.400034 0 180)
			(size 0.254 0.254)
			(drill 3.0226)
			(layers "*.Cu" "*.Mask")
			(clearance 1.7399)
			(thermal_gap 1.7399)
		)
		(pad "" np_thru_hole circle
			(at 8.400034 0 180)
			(size 0.254 0.254)
			(drill 3.0226)
			(layers "*.Cu" "*.Mask")
			(clearance 1.7399)
			(thermal_gap 1.7399)
		)
		(pad "1" thru_hole circle
			(at 8.400034 -7.29996 180)
			(size 2.5654 2.5654)
			(drill 1.8034)
			(layers "*.Cu" "*.Mask")
			(remove_unused_layers no)
			(net "FAN_2_TACH0")
			(clearance 0.127)
			(thermal_gap 0.127)
		)
		(pad "2" thru_hole circle
			(at 8.400034 -12.800076 180)
			(size 2.5654 2.5654)
			(drill 1.8034)
			(layers "*.Cu" "*.Mask")
			(remove_unused_layers no)
			(net "FAN_2_TACH1")
			(clearance 0.127)
			(thermal_gap 0.127)
		)
		(pad "3" thru_hole circle
			(at 4.19989 -7.29996 180)
			(size 2.5654 2.5654)
			(drill 1.8034)
			(layers "*.Cu" "*.Mask")
			(remove_unused_layers no)
			(net "FAN_2_PWM")
			(clearance 0.127)
			(thermal_gap 0.127)
		)
		(pad "4" thru_hole circle
			(at 4.19989 -12.800076 180)
			(size 2.5654 2.5654)
			(drill 1.8034)
			(layers "*.Cu" "*.Mask")
			(remove_unused_layers no)
			(net "FAN_2_PWM")
			(clearance 0.127)
			(thermal_gap 0.127)
		)
		(pad "5" thru_hole circle
			(at 0 -7.29996 180)
			(size 2.5654 2.5654)
			(drill 1.8034)
			(layers "*.Cu" "*.Mask")
			(remove_unused_layers no)
			(net "FAN_2_INS_N")
			(clearance 0.127)
			(thermal_gap 0.127)
		)
		(pad "6" thru_hole circle
			(at 0 -12.800076 180)
			(size 2.5654 2.5654)
			(drill 1.8034)
			(layers "*.Cu" "*.Mask")
			(remove_unused_layers no)
			(net "Net_1772")
			(clearance 0.127)
			(thermal_gap 0.127)
		)
		(pad "7" thru_hole circle
			(at -4.19989 -7.29996 180)
			(size 2.5654 2.5654)
			(drill 1.8034)
			(layers "*.Cu" "*.Mask")
			(remove_unused_layers no)
			(net "P12V_FAN2")
			(clearance 0.127)
			(thermal_gap 0.127)
		)
		(pad "8" thru_hole circle
			(at -4.19989 -12.800076 180)
			(size 2.5654 2.5654)
			(drill 1.8034)
			(layers "*.Cu" "*.Mask")
			(remove_unused_layers no)
			(net "P12V_FAN2")
			(clearance 0.127)
			(thermal_gap 0.127)
		)
		(pad "9" thru_hole circle
			(at -8.400034 -7.29996 180)
			(size 2.5654 2.5654)
			(drill 1.8034)
			(layers "*.Cu" "*.Mask")
			(remove_unused_layers no)
			(net "GND")
			(clearance 0.127)
			(thermal_gap 0.127)
		)
		(pad "10" thru_hole circle
			(at -8.400034 -12.800076 180)
			(size 2.5654 2.5654)
			(drill 1.8034)
			(layers "*.Cu" "*.Mask")
			(remove_unused_layers no)
			(net "GND")
			(clearance 0.127)
			(thermal_gap 0.127)
		)
		(zone
			(layers "F.Cu" "B.Cu" "In1.Cu" "In2.Cu" "In3.Cu" "In4.Cu" "In5.Cu" "In6.Cu")
			(hatch none 0.5)
			(connect_pads
				(clearance 0)
			)
			(min_thickness 0.25)
			(keepout
				(tracks not_allowed)
				(vias allowed)
				(pads allowed)
				(copperpour not_allowed)
				(footprints allowed)
			)
			(placement
				(enabled no)
				(sheetname "")
			)
			(fill
				(thermal_gap 0.5)
				(thermal_bridge_width 0.5)
				(island_removal_mode 0)
			)
			(polygon
				(pts
					(arc
						(start 335.81594 -379.899926)
						(mid 332.18374 -379.899926)
						(end 335.81594 -379.899926)
					)
				)
			)
		)
		(zone
			(layers "F.Cu" "B.Cu" "In1.Cu" "In2.Cu" "In3.Cu" "In4.Cu" "In5.Cu" "In6.Cu")
			(hatch none 0.5)
			(connect_pads
				(clearance 0)
			)
			(min_thickness 0.25)
			(keepout
				(tracks not_allowed)
				(vias allowed)
				(pads allowed)
				(copperpour not_allowed)
				(footprints allowed)
			)
			(placement
				(enabled no)
				(sheetname "")
			)
			(fill
				(thermal_gap 0.5)
				(thermal_bridge_width 0.5)
				(island_removal_mode 0)
			)
			(polygon
				(pts
					(arc
						(start 352.616008 -379.899926)
						(mid 348.983808 -379.899926)
						(end 352.616008 -379.899926)
					)
				)
			)
		)
	)
	(footprint ""
		(layer "F.Cu")
		(at 115.316 -16.637 -90)
		(property "Reference" "Q137"
			(at 0 0 270)
			(layer "F.SilkS")
			(hide yes)
			(effects
				(font
					(size 1.27 1.27)
				)
			)
		)
		(property "Value" "2N7002KDW-GP"
			(at -2.3622 -8.2042 270)
			(unlocked yes)
			(layer "F.Fab")
			(hide yes)
			(effects
				(font
					(size 1.016 1.016)
					(thickness 0.1524)
				)
			)
		)
		(property "Device Type" "SOT-363H44"
			(at -2.3622 -10.1092 270)
			(unlocked yes)
			(layer "F.Fab")
			(hide yes)
			(effects
				(font
					(size 1.016 1.016)
					(thickness 0.1524)
				)
			)
		)
		(duplicate_pad_numbers_are_jumpers no)
		(fp_line
			(start -1.4478 1.7018)
			(end 1.4478 1.7018)
			(stroke
				(width 0.1524)
				(type default)
			)
			(layer "F.SilkS")
		)
		(fp_line
			(start 1.4478 1.7018)
			(end 1.4478 -1.7018)
			(stroke
				(width 0.1524)
				(type default)
			)
			(layer "F.SilkS")
		)
		(fp_line
			(start -1.27 1.524)
			(end -1.27 0.6604)
			(stroke
				(width 0.4826)
				(type default)
			)
			(layer "F.SilkS")
		)
		(fp_line
			(start -1.4478 -1.7018)
			(end -1.4478 1.7018)
			(stroke
				(width 0.1524)
				(type default)
			)
			(layer "F.SilkS")
		)
		(fp_line
			(start 1.4478 -1.7018)
			(end -1.4478 -1.7018)
			(stroke
				(width 0.1524)
				(type default)
			)
			(layer "F.SilkS")
		)
		(fp_poly
			(pts
				(xy -1.524 -1.778) (xy 1.524 -1.778) (xy 1.524 1.778) (xy -1.524 1.778)
			)
			(stroke
				(width 0)
				(type default)
			)
			(fill no)
			(layer "F.CrtYd")
		)
		(fp_poly
			(pts
				(xy -1.524 -1.778) (xy 1.524 -1.778) (xy 1.524 1.778) (xy -1.524 1.778)
			)
			(stroke
				(width 0)
				(type default)
			)
			(fill no)
			(layer "F.Fab")
		)
		(pad "1" smd rect
			(at -0.65024 0.9398 270)
			(size 0.4064 1.016)
			(layers "F.Cu" "F.Mask" "F.Paste")
			(net "GND")
		)
		(pad "2" smd rect
			(at 0 0.9398 270)
			(size 0.4064 1.016)
			(layers "F.Cu" "F.Mask" "F.Paste")
			(net "SW_PWR_R_HDD27")
		)
		(pad "3" smd rect
			(at 0.65024 0.9398 270)
			(size 0.4064 1.016)
			(layers "F.Cu" "F.Mask" "F.Paste")
			(net "SW_HDD_P27")
		)
		(pad "4" smd rect
			(at 0.65024 -0.9398 270)
			(size 0.4064 1.016)
			(layers "F.Cu" "F.Mask" "F.Paste")
			(net "GND")
		)
		(pad "5" smd rect
			(at 0 -0.9398 270)
			(size 0.4064 1.016)
			(layers "F.Cu" "F.Mask" "F.Paste")
			(net "SW_HDD_G27")
		)
		(pad "6" smd rect
			(at -0.65024 -0.9398 270)
			(size 0.4064 1.016)
			(layers "F.Cu" "F.Mask" "F.Paste")
			(net "SW_HDD_R27")
		)
	)
	(footprint ""
		(layer "F.Cu")
		(at 466.934804 -372.2624 -90)
		(property "Reference" "R980"
			(at 0 0 270)
			(layer "F.SilkS")
			(hide yes)
			(effects
				(font
					(size 1.27 1.27)
				)
			)
		)
		(property "Value" "270R5J-2-GP"
			(at 0 -8.9535 270)
			(unlocked yes)
			(layer "F.Fab")
			(hide yes)
			(effects
				(font
					(size 1.27 1.016)
					(thickness 0.1524)
				)
			)
		)
		(property "Device Type" "R805H24"
			(at 0 -10.6299 270)
			(unlocked yes)
			(layer "F.Fab")
			(hide yes)
			(effects
				(font
					(size 1.27 1.016)
					(thickness 0.1524)
				)
			)
		)
		(duplicate_pad_numbers_are_jumpers no)
		(fp_line
			(start -0.889 1.7018)
			(end 0.889 1.7018)
			(stroke
				(width 0.1524)
				(type default)
			)
			(layer "F.SilkS")
		)
		(fp_line
			(start 0.889 1.7018)
			(end 0.889 -0.508)
			(stroke
				(width 0.1524)
				(type default)
			)
			(layer "F.SilkS")
		)
		(fp_line
			(start -0.889 0.0762)
			(end -0.889 1.7018)
			(stroke
				(width 0.1524)
				(type default)
			)
			(layer "F.SilkS")
		)
		(fp_line
			(start -0.889 -1.7018)
			(end -0.889 0.2794)
			(stroke
				(width 0.1524)
				(type default)
			)
			(layer "F.SilkS")
		)
		(fp_line
			(start 0.889 -1.7018)
			(end 0.889 -0.381)
			(stroke
				(width 0.1524)
				(type default)
			)
			(layer "F.SilkS")
		)
		(fp_line
			(start 0.889 -1.7018)
			(end -0.889 -1.7018)
			(stroke
				(width 0.1524)
				(type default)
			)
			(layer "F.SilkS")
		)
		(fp_poly
			(pts
				(xy 0.9652 -1.778) (xy 0.9652 1.778) (xy -0.9652 1.778) (xy -0.9652 -1.778)
			)
			(stroke
				(width 0)
				(type default)
			)
			(fill no)
			(layer "F.CrtYd")
		)
		(fp_rect
			(start -0.9652 1.778)
			(end 0.9652 -1.778)
			(stroke
				(width 0)
				(type default)
			)
			(fill no)
			(layer "F.Fab")
		)
		(pad "1" smd rect
			(at 0 -0.9652 270)
			(size 1.397 1.143)
			(layers "F.Cu" "F.Mask" "F.Paste")
			(net "FAN_LED_BLUE3")
		)
		(pad "2" smd rect
			(at 0 0.9652 270)
			(size 1.397 1.143)
			(layers "F.Cu" "F.Mask" "F.Paste")
			(net "FAN_BLUE3")
		)
	)
	(footprint ""
		(layer "F.Cu")
		(at 46.355 -131.572 90)
		(property "Reference" "R383"
			(at 0 0 90)
			(layer "F.SilkS")
			(hide yes)
			(effects
				(font
					(size 1.27 1.27)
				)
			)
		)
		(property "Value" "4K7R2J-2-GP"
			(at 0.064008 -3.993896 90)
			(unlocked yes)
			(layer "F.Fab")
			(hide yes)
			(effects
				(font
					(size 1.016 1.016)
					(thickness 0.1524)
				)
			)
		)
		(property "Device Type" "R402H16"
			(at 0.064008 -5.517896 90)
			(unlocked yes)
			(layer "F.Fab")
			(hide yes)
			(effects
				(font
					(size 1.016 1.016)
					(thickness 0.1524)
				)
			)
		)
		(duplicate_pad_numbers_are_jumpers no)
		(fp_line
			(start 0.508 -0.9398)
			(end -0.508 -0.9398)
			(stroke
				(width 0.1524)
				(type default)
			)
			(layer "F.SilkS")
		)
		(fp_line
			(start -0.508 -0.9398)
			(end -0.508 0.9398)
			(stroke
				(width 0.1524)
				(type default)
			)
			(layer "F.SilkS")
		)
		(fp_rect
			(start -0.508 0.9398)
			(end 0.508 -0.9398)
			(stroke
				(width 0)
				(type default)
			)
			(fill no)
			(layer "F.CrtYd")
		)
		(fp_rect
			(start -0.508 0.9398)
			(end 0.508 -0.9398)
			(stroke
				(width 0)
				(type default)
			)
			(fill no)
			(layer "F.Fab")
		)
		(pad "1" smd custom
			(at 0 -0.4445 90)
			(size 0.1397 0.1397)
			(layers "F.Cu" "F.Mask" "F.Paste")
			(net "P12V_B")
			(options
				(clearance outline)
				(anchor circle)
			)
			(primitives
				(gr_poly
					(pts
						(arc
							(start -0.1778 -0.2794)
							(mid -0.249642 -0.249642)
							(end -0.2794 -0.1778)
						)
						(arc
							(start -0.2794 0.1778)
							(mid -0.249642 0.249642)
							(end -0.1778 0.2794)
						)
						(arc
							(start 0.1778 0.2794)
							(mid 0.249642 0.249642)
							(end 0.2794 0.1778)
						)
						(arc
							(start 0.2794 -0.1778)
							(mid 0.249642 -0.249642)
							(end 0.1778 -0.2794)
						)
					)
					(width 0)
					(fill yes)
				)
			)
		)
		(pad "2" smd custom
			(at 0 0.4445 90)
			(size 0.1397 0.1397)
			(layers "F.Cu" "F.Mask" "F.Paste")
			(net "SW_HDD_R13")
			(options
				(clearance outline)
				(anchor circle)
			)
			(primitives
				(gr_poly
					(pts
						(arc
							(start -0.1778 -0.2794)
							(mid -0.249642 -0.249642)
							(end -0.2794 -0.1778)
						)
						(arc
							(start -0.2794 0.1778)
							(mid -0.249642 0.249642)
							(end -0.1778 0.2794)
						)
						(arc
							(start 0.1778 0.2794)
							(mid 0.249642 0.249642)
							(end 0.2794 0.1778)
						)
						(arc
							(start 0.2794 -0.1778)
							(mid 0.249642 -0.249642)
							(end 0.1778 -0.2794)
						)
					)
					(width 0)
					(fill yes)
				)
			)
		)
	)
	(footprint ""
		(layer "F.Cu")
		(at 23.876 -42.291)
		(property "Reference" "C347"
			(at 0 0 0)
			(layer "F.SilkS")
			(hide yes)
			(effects
				(font
					(size 1.27 1.27)
				)
			)
		)
		(property "Value" "SC4D7U25V5KX-1-GP"
			(at -0.0762 -6.1214 0)
			(unlocked yes)
			(layer "F.Fab")
			(hide yes)
			(effects
				(font
					(size 1.016 1.016)
					(thickness 0.1524)
				)
			)
		)
		(property "Device Type" "C805H58"
			(at -0.0762 -8.1534 0)
			(unlocked yes)
			(layer "F.Fab")
			(hide yes)
			(effects
				(font
					(size 1.016 1.016)
					(thickness 0.1524)
				)
			)
		)
		(duplicate_pad_numbers_are_jumpers no)
		(fp_line
			(start 0.635 0)
			(end -0.635 0)
			(stroke
				(width 0.508)
				(type default)
			)
			(layer "F.SilkS")
		)
		(fp_rect
			(start -0.9652 1.778)
			(end 0.9652 -1.778)
			(stroke
				(width 0)
				(type default)
			)
			(fill no)
			(layer "F.CrtYd")
		)
		(fp_poly
			(pts
				(xy -0.9652 -1.778) (xy 0.9652 -1.778) (xy 0.9652 1.778) (xy -0.9652 1.778)
			)
			(stroke
				(width 0)
				(type default)
			)
			(fill no)
			(layer "F.Fab")
		)
		(pad "1" smd rect
			(at 0 -0.9652)
			(size 1.397 1.143)
			(layers "F.Cu" "F.Mask" "F.Paste")
			(net "P12V_HDD24")
		)
		(pad "2" smd rect
			(at 0 0.9652)
			(size 1.397 1.143)
			(layers "F.Cu" "F.Mask" "F.Paste")
			(net "GND")
		)
	)
)
